FILE_TYPE = CONNECTIVITY;
{Allegro Design Entry HDL 17.4-2019 S026 (4007227) 1/17/2022}
"PAGE_NUMBER" = 419;
0"NC";
1"GND\g";
2"GND\g";
3"GND\g";
4"GND\g";
5"GND\g";
6"GND\g";
7"P1V8_CPU0_RT_1D\g";
8"GND\g";
9"P1V8_CPU0_RT_1D\g";
10"GND\g";
11"GND\g";
12"P1V8_CPU0_RT_1D\g";
13"GND\g";
14"GND\g";
15"P1V8_CPU0_RT_1D\g";
16"SMB_RT_CPU0_P2_ROM_MUX_1D_SDA";
17"SMB_RT_CPU0_P2_ROM_MUX_1D_R_SDA";
18"SMB_RT_CPU0_P2_ROM_MUX_1D_SCL";
19"SMB_RT_CPU0_P2_ROM_MUX_1D_R_SCL";
20"RT_CPU0_P2_SCAN_MODE";
21"JTAG_TCK_RT_CPU0_P2";
22"JTAG_TMS_RT_CPU0_P2";
23"JTAG_TDI_RT_CPU0_P2";
24"RST_RT_CPU0_P2_RESET_N";
25"RST_RT_CPU0_P2_PERST_N";
26"JTAG_TDO_RT_CPU0_P2";
27"P1V8_CPU0_RT_1D\g";
28"CLKREQ_RT_CPU0_P2_N";
29"RT_CPU0_P2_SCAN_MODE";
30"RXDET_BYP_RT_CPU0_P2";
31"MODE_RT_CPU0_P2";
32"JTAG_TDO_RT_CPU0_P2";
33"JTAG_TCK_RT_CPU0_P2";
34"RST_RT_CPU0_P2_PERST_R_N";
35"P1V8_CPU0_RT_1D\g";
36"GND\g";
37"GND\g";
38"P1V8_CPU0_RT_1D\g";
39"RXDET_BYP_RT_CPU0_P2";
40"GPIO2_RT_CPU0_P2";
41"RST_RT_CPU0_P2_RESET_R_N";
42"RST_RT_CPU0_P2_PERST_R_N";
43"RT_CPU0_P2_ADDR3";
44"MODE_RT_CPU0_P2";
45"TEST2_RT_CPU0_P2";
46"TEST1_RT_CPU0_P2";
47"GPIO2_RT_CPU0_P2";
48"JTAG_TEST_MODE_RT_CPU0_P2";
49"SMB_RT_CPU0_P2_R_SCL";
50"GPIO3_RT_CPU0_P2";
51"TEST0_RT_CPU0_P2";
52"GPIO3_RT_CPU0_P2";
53"SMB_RT_CPU0_P2_R_SDA";
54"SMB_RT_CPU0_P2_R2_SDA";
55"SMB_RT_CPU0_P2_R2_SCL";
56"RT_CPU0_P2_ADDR1";
57"RT_CPU0_P2_ADDR2";
58"RT_CPU0_P2_ADDR3";
59"TEST0_RT_CPU0_P2";
60"RT_CPU0_P2_ADDR2";
61"RT_CPU0_P2_ADDR1";
62"TEST1_RT_CPU0_P2";
63"CLK_100M_RETIMER_CPU0_P2_DP";
64"TEST2_RT_CPU0_P2";
65"CLK_100M_RETIMER_CPU0_P2_R_DP";
66"CLK_100M_RETIMER_CPU0_P2_R_DN";
67"CLK_100M_RETIMER_CPU0_P2_DN";
68"RST_RT_CPU0_P2_RESET_R_N";
69"JTAG_TRST_RT_CPU0_P2_N";
70"JTAG_TDI_RT_CPU0_P2";
71"JTAG_TMS_RT_CPU0_P2";
72"JTAG_TEST_MODE_RT_CPU0_P2";
%"Q_RES"
"2","(-8975,5900)","0","pure_quanta","I10";
;
LOCATION"R1069"
$SEC"1"
CDS_SEC"1"
TOLERANCE"5%"
VALUE"4.7K"
PACK_TYPE"0201LF"
MATERIAL"EMPTY"
WATTAGE"1/20W"
CDS_LIB"pure_quanta"
PART_NUMBER"CS24701JE04";
"A"
$PN"1"38;
"B"
$PN"2"47;
%"UNIVERSAL_GND"
"1","(-1975,2200)","1","pure_quanta_power","I100";
;
CDS_LIB"pure_quanta_power"
HDL_POWER"GND";
"A"1;
%"Q_RES"
"2","(-9000,3350)","0","pure_quanta","I102";
;
LOCATION"R1064"
$SEC"1"
CDS_SEC"1"
PACK_TYPE"0201LF"
MATERIAL"CHIP"
WATTAGE"1/20W"
TOLERANCE"1%"
VALUE"200"
CDS_LIB"pure_quanta"
PART_NUMBER"CS12001FE12";
"A"
$PN"1"20;
"B"
$PN"2"5;
%"Q_RES"
"2","(-8350,5900)","0","pure_quanta","I11";
;
LOCATION"R1073"
$SEC"1"
CDS_SEC"1"
MATERIAL"EMPTY"
PACK_TYPE"0201LF"
WATTAGE"1/20W"
TOLERANCE"5%"
VALUE"4.7K"
CDS_LIB"pure_quanta"
PART_NUMBER"CS24701JE04";
"A"
$PN"1"38;
"B"
$PN"2"51;
%"Q_RES"
"2","(-1450,1300)","0","pure_quanta","I116";
;
LOCATION"R1476"
$SEC"1"
CDS_SEC"1"
PACK_TYPE"0201LF"
MATERIAL"EMPTY"
WATTAGE"1/20W"
TOLERANCE"5%"
VALUE"4.7K"
CDS_LIB"pure_quanta"
PART_NUMBER"CS24701JE04";
"A"
$PN"1"27;
"B"
$PN"2"23;
%"Q_RES"
"2","(-1175,1300)","0","pure_quanta","I117";
;
LOCATION"R1477"
$SEC"1"
CDS_SEC"1"
PACK_TYPE"0201LF"
VALUE"4.7K"
MATERIAL"EMPTY"
TOLERANCE"5%"
WATTAGE"1/20W"
CDS_LIB"pure_quanta"
PART_NUMBER"CS24701JE04";
"A"
$PN"1"27;
"B"
$PN"2"22;
%"Q_RES"
"2","(-900,1300)","0","pure_quanta","I118";
;
LOCATION"R1478"
$SEC"1"
CDS_SEC"1"
VALUE"1K"
TOLERANCE"1%"
WATTAGE"1/20W"
PACK_TYPE"0201LF"
MATERIAL"EMPTY"
CDS_LIB"pure_quanta"
PART_NUMBER"CS21001FE07";
"A"
$PN"1"27;
"B"
$PN"2"26;
%"GND"
"1","(-625,375)","0","pure_quanta_power","I119";
;
SIZE"1B"
BOM_COST"MEM"
CDS_LIB"pure_quanta_power"
HDL_POWER"GND";
"A<SIZE-1..0>\NAC"2;
%"P1V0"
"1","(-8975,6300)","0","pure_quanta_power","I12";
;
HDL_POWER"P1V8_CPU0_RT_1D"
CDS_LIB"pure_quanta_power";
"A"38;
%"Q_RES"
"2","(-625,675)","0","pure_quanta","I120";
;
LOCATION"R1401"
$SEC"1"
CDS_SEC"1"
PACK_TYPE"0201LF"
MATERIAL"CHIP"
WATTAGE"1/20W"
VALUE"4.7K"
TOLERANCE"5%"
CDS_LIB"pure_quanta"
PART_NUMBER"CS24701JE04";
"A"
$PN"1"21;
"B"
$PN"2"2;
%"Q_RES"
"2","(-625,1325)","0","pure_quanta","I121";
;
LOCATION"R1479"
$SEC"1"
CDS_SEC"1"
WATTAGE"1/20W"
MATERIAL"EMPTY"
TOLERANCE"5%"
PACK_TYPE"0201LF"
VALUE"4.7K"
CDS_LIB"pure_quanta"
PART_NUMBER"CS24701JE04";
"A"
$PN"1"27;
"B"
$PN"2"21;
%"P1V0"
"1","(-625,1625)","0","pure_quanta_power","I122";
;
HDL_POWER"P1V8_CPU0_RT_1D"
CDS_LIB"pure_quanta_power";
"A"27;
%"UNIVERSAL_GND"
"1","(-6325,300)","0","pure_quanta_power","I15";
;
CDS_LIB"pure_quanta_power"
HDL_POWER"GND";
"A"3;
%"UNIVERSAL_GND"
"1","(-6175,300)","0","pure_quanta_power","I16";
;
CDS_LIB"pure_quanta_power"
HDL_POWER"GND";
"A"4;
%"Q_RES"
"2","(-6325,625)","2","pure_quanta","I17";
;
LOCATION"R631"
$SEC"1"
CDS_SEC"1"
PACK_TYPE"0201LF"
MATERIAL"EMPTY"
WATTAGE"1/20W"
VALUE"51.1"
TOLERANCE"1%"
CDS_LIB"pure_quanta"
PART_NUMBER"CS05111FE00";
"A"
$PN"1"67;
"B"
$PN"2"3;
%"Q_RES"
"2","(-6175,625)","0","pure_quanta","I18";
;
LOCATION"R634"
$SEC"1"
CDS_SEC"1"
VALUE"51.1"
WATTAGE"1/20W"
MATERIAL"EMPTY"
PACK_TYPE"0201LF"
TOLERANCE"1%"
CDS_LIB"pure_quanta"
PART_NUMBER"CS05111FE00";
"A"
$PN"1"63;
"B"
$PN"2"4;
%"Q_RES"
"1","(-6625,1100)","0","pure_quanta","I19";
;
LOCATION"R613"
SEC"1"
WATTAGE"1/20W"
MATERIAL"CHIP"
TOLERANCE"5%"
VALUE"0"
PACK_TYPE"0201LF"
SEC_TYPE"0201LF"
CDS_LIB"pure_quanta"
PART_NUMBER"CS00001JE10";
"B"
$PN"2"63;
"A"
$PN"1"65;
%"Q_RES"
"1","(-6625,950)","0","pure_quanta","I20";
;
LOCATION"R614"
SEC"1"
PACK_TYPE"0201LF"
MATERIAL"CHIP"
SEC_TYPE"0201LF"
WATTAGE"1/20W"
VALUE"0"
TOLERANCE"5%"
CDS_LIB"pure_quanta"
PART_NUMBER"CS00001JE10";
"B"
$PN"2"67;
"A"
$PN"1"66;
%"Q_RES"
"1","(-6350,1450)","0","pure_quanta","I21";
;
LOCATION"R681"
$SEC"1"
CDS_SEC"1"
PACK_TYPE"0201LF"
WATTAGE"1/20W"
MATERIAL"CHIP"
CDS_LIB"pure_quanta"
VALUE"49.9"
TOLERANCE"1%"
PART_NUMBER"CS04991FE06";
"B"
$PN"2"17;
"A"
$PN"1"16;
%"Q_RES"
"1","(-6350,1550)","0","pure_quanta","I22";
;
LOCATION"R680"
$SEC"1"
CDS_SEC"1"
WATTAGE"1/20W"
MATERIAL"CHIP"
PACK_TYPE"0201LF"
VALUE"49.9"
TOLERANCE"1%"
CDS_LIB"pure_quanta"
PART_NUMBER"CS04991FE06";
"B"
$PN"2"19;
"A"
$PN"1"18;
%"Q_RES"
"1","(-6375,2800)","0","pure_quanta","I29";
;
LOCATION"R1067"
$SEC"1"
CDS_SEC"1"
MATERIAL"CHIP"
WATTAGE"1/20W"
VALUE"0"
TOLERANCE"5%"
PACK_TYPE"0201LF"
CDS_LIB"pure_quanta"
PART_NUMBER"CS00001JE10";
"B"
$PN"2"55;
"A"
$PN"1"49;
%"UNIVERSAL_GND"
"1","(-9000,3075)","0","pure_quanta_power","I3";
;
CDS_LIB"pure_quanta_power"
HDL_POWER"GND";
"A"5;
%"Q_RES"
"1","(-6375,2700)","0","pure_quanta","I30";
;
LOCATION"R1068"
$SEC"1"
CDS_SEC"1"
CDS_LIB"pure_quanta"
PACK_TYPE"0201LF"
MATERIAL"CHIP"
TOLERANCE"5%"
VALUE"0"
WATTAGE"1/20W"
PART_NUMBER"CS00001JE10";
"B"
$PN"2"54;
"A"
$PN"1"53;
%"Q_RES"
"2","(-8050,4925)","0","pure_quanta","I36";
;
LOCATION"R1076"
$SEC"1"
CDS_SEC"1"
WATTAGE"1/20W"
TOLERANCE"5%"
PACK_TYPE"0201LF"
MATERIAL"CHIP"
VALUE"4.7K"
CDS_LIB"pure_quanta"
PART_NUMBER"CS24701JE04";
"A"
$PN"1"46;
"B"
$PN"2"37;
%"Q_RES"
"2","(-7750,4925)","0","pure_quanta","I37";
;
LOCATION"R1078"
$SEC"1"
CDS_SEC"1"
PACK_TYPE"0201LF"
VALUE"4.7K"
TOLERANCE"5%"
MATERIAL"CHIP"
WATTAGE"1/20W"
CDS_LIB"pure_quanta"
PART_NUMBER"CS24701JE04";
"A"
$PN"1"45;
"B"
$PN"2"37;
%"UNIVERSAL_GND"
"1","(-7450,4450)","0","pure_quanta_power","I38";
;
CDS_LIB"pure_quanta_power"
HDL_POWER"GND";
"A"37;
%"Q_RES"
"2","(-7450,4900)","0","pure_quanta","I39";
;
LOCATION"R1079"
$SEC"1"
CDS_SEC"1"
TOLERANCE"5%"
VALUE"4.7K"
PACK_TYPE"0201LF"
MATERIAL"CHIP"
WATTAGE"1/20W"
CDS_LIB"pure_quanta"
PART_NUMBER"CS24701JE04";
"A"
$PN"1"48;
"B"
$PN"2"37;
%"Q_RES"
"2","(-8050,5850)","0","pure_quanta","I40";
;
LOCATION"R1075"
$SEC"1"
CDS_SEC"1"
TOLERANCE"5%"
VALUE"4.7K"
PACK_TYPE"0201LF"
MATERIAL"EMPTY"
WATTAGE"1/20W"
CDS_LIB"pure_quanta"
PART_NUMBER"CS24701JE04";
"A"
$PN"1"38;
"B"
$PN"2"46;
%"Q_RES"
"2","(-7750,5875)","0","pure_quanta","I41";
;
LOCATION"R1077"
$SEC"1"
CDS_SEC"1"
WATTAGE"1/20W"
MATERIAL"EMPTY"
VALUE"4.7K"
TOLERANCE"5%"
PACK_TYPE"0201LF"
CDS_LIB"pure_quanta"
PART_NUMBER"CS24701JE04";
"A"
$PN"1"38;
"B"
$PN"2"45;
%"Q_RES"
"2","(-7450,5900)","0","pure_quanta","I42";
;
LOCATION"R1066"
$SEC"1"
CDS_SEC"1"
MATERIAL"EMPTY"
WATTAGE"1/20W"
VALUE"4.7K"
TOLERANCE"5%"
PACK_TYPE"0201LF"
CDS_LIB"pure_quanta"
PART_NUMBER"CS24701JE04";
"A"
$PN"1"38;
"B"
$PN"2"48;
%"UNIVERSAL_GND"
"1","(-5050,5100)","0","pure_quanta_power","I49";
;
CDS_LIB"pure_quanta_power"
HDL_POWER"GND";
"A"6;
%"Q_RES"
"2","(-9000,4025)","0","pure_quanta","I5";
;
LOCATION"R1063"
$SEC"1"
CDS_SEC"1"
MATERIAL"EMPTY"
VALUE"4.7K"
TOLERANCE"5%"
WATTAGE"1/20W"
PACK_TYPE"0201LF"
CDS_LIB"pure_quanta"
PART_NUMBER"CS24701JE04";
"A"
$PN"1"9;
"B"
$PN"2"20;
%"Q_RES"
"2","(-5050,5450)","0","pure_quanta","I50";
;
LOCATION"R1048"
$SEC"1"
CDS_SEC"1"
MATERIAL"EMPTY"
WATTAGE"1/20W"
TOLERANCE"5%"
VALUE"4.7K"
PACK_TYPE"0201LF"
CDS_LIB"pure_quanta"
PART_NUMBER"CS24701JE04";
"A"
$PN"1"44;
"B"
$PN"2"6;
%"Q_RES"
"2","(-5050,5975)","0","pure_quanta","I51";
;
LOCATION"R1080"
$SEC"1"
CDS_SEC"1"
PACK_TYPE"0201LF"
WATTAGE"1/20W"
TOLERANCE"5%"
MATERIAL"CHIP"
VALUE"4.7K"
CDS_LIB"pure_quanta"
PART_NUMBER"CS24701JE04";
"A"
$PN"1"7;
"B"
$PN"2"44;
%"P1V0"
"1","(-5050,6300)","0","pure_quanta_power","I53";
;
HDL_POWER"P1V8_CPU0_RT_1D"
CDS_LIB"pure_quanta_power";
"A"7;
%"UNIVERSAL_GND"
"1","(-3075,1600)","1","pure_quanta_power","I54";
;
CDS_LIB"pure_quanta_power"
HDL_POWER"GND";
"A"8;
%"Q_RES"
"1","(-2600,2000)","0","pure_quanta","I55";
;
LOCATION"R1054"
$SEC"1"
CDS_SEC"1"
PACK_TYPE"0201LF"
VALUE"0"
CDS_LIB"pure_quanta"
MATERIAL"CHIP"
TOLERANCE"5%"
WATTAGE"1/20W"
PART_NUMBER"CS00001JE10";
"B"
$PN"2"68;
"A"
$PN"1"24;
%"Q_RES"
"1","(-2600,2100)","0","pure_quanta","I56";
;
LOCATION"R1047"
SEC"1"
VALUE"0"
PACK_TYPE"0201LF"
WATTAGE"1/20W"
TOLERANCE"5%"
MATERIAL"CHIP"
SEC_TYPE"0201LF"
CDS_LIB"pure_quanta"
PART_NUMBER"CS00001JE10";
"B"
$PN"2"34;
"A"
$PN"1"25;
%"P1V0"
"1","(-9000,4350)","0","pure_quanta_power","I6";
;
HDL_POWER"P1V8_CPU0_RT_1D"
CDS_LIB"pure_quanta_power";
"A"9;
%"UNIVERSAL_GND"
"1","(-3500,4700)","0","pure_quanta_power","I64";
;
CDS_LIB"pure_quanta_power"
HDL_POWER"GND";
"A"36;
%"Q_RES"
"2","(-3500,5125)","0","pure_quanta","I65";
;
LOCATION"R1056"
$SEC"1"
CDS_SEC"1"
PACK_TYPE"0201LF"
VALUE"1K"
MATERIAL"EMPTY"
TOLERANCE"1%"
WATTAGE"1/20W"
CDS_LIB"pure_quanta"
PART_NUMBER"CS21001FE07";
"A"
$PN"1"43;
"B"
$PN"2"36;
%"Q_RES"
"2","(-3200,5125)","0","pure_quanta","I66";
;
LOCATION"R1058"
$SEC"1"
CDS_SEC"1"
VALUE"20K"
TOLERANCE"1%"
WATTAGE"1/20W"
MATERIAL"CHIP"
PACK_TYPE"0201LF"
CDS_LIB"pure_quanta"
PART_NUMBER"CS32001FE00";
"A"
$PN"1"60;
"B"
$PN"2"36;
%"Q_RES"
"2","(-3500,5900)","0","pure_quanta","I67";
;
LOCATION"R1055"
$SEC"1"
CDS_SEC"1"
PACK_TYPE"0201LF"
TOLERANCE"1%"
VALUE"1K"
MATERIAL"CHIP"
WATTAGE"1/20W"
CDS_LIB"pure_quanta"
PART_NUMBER"CS21001FE07";
"A"
$PN"1"35;
"B"
$PN"2"43;
%"Q_RES"
"2","(-3200,5900)","0","pure_quanta","I68";
;
LOCATION"R1057"
$SEC"1"
CDS_SEC"1"
TOLERANCE"1%"
VALUE"1K"
WATTAGE"1/20W"
MATERIAL"EMPTY"
PACK_TYPE"0201LF"
CDS_LIB"pure_quanta"
PART_NUMBER"CS21001FE07";
"A"
$PN"1"35;
"B"
$PN"2"60;
%"Q_RES"
"2","(-2850,5125)","0","pure_quanta","I69";
;
LOCATION"R1060"
$SEC"1"
CDS_SEC"1"
PACK_TYPE"0201LF"
VALUE"1K"
TOLERANCE"1%"
WATTAGE"1/20W"
MATERIAL"CHIP"
CDS_LIB"pure_quanta"
PART_NUMBER"CS21001FE07";
"A"
$PN"1"61;
"B"
$PN"2"36;
%"Q_RES"
"2","(-8975,4950)","0","pure_quanta","I7";
;
LOCATION"R1070"
$SEC"1"
CDS_SEC"1"
VALUE"10K"
TOLERANCE"1%"
WATTAGE"1/20W"
MATERIAL"CHIP"
PACK_TYPE"0201LF"
CDS_LIB"pure_quanta"
PART_NUMBER"CS31001FE17";
"A"
$PN"1"47;
"B"
$PN"2"37;
%"Q_RES"
"2","(-2850,5875)","0","pure_quanta","I70";
;
LOCATION"R1059"
$SEC"1"
CDS_SEC"1"
WATTAGE"1/20W"
TOLERANCE"1%"
VALUE"1K"
PACK_TYPE"0201LF"
MATERIAL"EMPTY"
CDS_LIB"pure_quanta"
PART_NUMBER"CS21001FE07";
"A"
$PN"1"35;
"B"
$PN"2"61;
%"P1V0"
"1","(-3500,6325)","0","pure_quanta_power","I71";
;
HDL_POWER"P1V8_CPU0_RT_1D"
CDS_LIB"pure_quanta_power";
"A"35;
%"GND"
"1","(-1500,4750)","0","pure_quanta_power","I72";
;
CDS_LIB"pure_quanta_power"
SIZE"1B"
BOM_COST"MEM"
HDL_POWER"GND";
"A<SIZE-1..0>\NAC"10;
%"GND"
"1","(-1325,4775)","0","pure_quanta_power","I73";
;
SIZE"1B"
BOM_COST"MEM"
CDS_LIB"pure_quanta_power"
HDL_POWER"GND";
"A<SIZE-1..0>\NAC"11;
%"Q_RES"
"2","(-1500,5125)","2","pure_quanta","I76";
;
LOCATION"R1062"
$SEC"1"
CDS_SEC"1"
TOLERANCE"1%"
WATTAGE"1/20W"
VALUE"10K"
MATERIAL"CHIP"
PACK_TYPE"0201LF"
CDS_LIB"pure_quanta"
PART_NUMBER"CS31001FE17";
"A"
$PN"1"41;
"B"
$PN"2"10;
%"Q_RES"
"2","(-1325,5125)","0","pure_quanta","I77";
;
LOCATION"R1061"
$SEC"1"
CDS_SEC"1"
MATERIAL"CHIP"
TOLERANCE"1%"
PACK_TYPE"0201LF"
VALUE"10K"
WATTAGE"1/20W"
CDS_LIB"pure_quanta"
PART_NUMBER"CS31001FE17";
"A"
$PN"1"42;
"B"
$PN"2"11;
%"Q_RES"
"2","(-1500,5950)","2","pure_quanta","I78";
;
LOCATION"R1065"
$SEC"1"
CDS_SEC"1"
TOLERANCE"5%"
VALUE"4.7K"
MATERIAL"EMPTY"
WATTAGE"1/20W"
PACK_TYPE"0201LF"
CDS_LIB"pure_quanta"
PART_NUMBER"CS24701JE04";
"A"
$PN"1"12;
"B"
$PN"2"41;
%"Q_RES"
"2","(-8675,4950)","0","pure_quanta","I8";
;
LOCATION"R1072"
$SEC"1"
CDS_SEC"1"
WATTAGE"1/20W"
PACK_TYPE"0201LF"
MATERIAL"CHIP"
TOLERANCE"1%"
VALUE"10K"
CDS_LIB"pure_quanta"
PART_NUMBER"CS31001FE17";
"A"
$PN"1"52;
"B"
$PN"2"37;
%"P1V0"
"1","(-1500,6200)","0","pure_quanta_power","I81";
;
HDL_POWER"P1V8_CPU0_RT_1D"
CDS_LIB"pure_quanta_power";
"A"12;
%"PT5161LRS"
"3","(-4400,2250)","0","pure_quanta","I83";
;
LOCATION"U6012"
$SEC"3"
CDS_SEC"3"
MATERIAL"IC"
PART_TYPE"SMLF"
VALUE"PT5161LRS"
CDS_LIB"pure_quanta"
CDS_LMAN_SYM_OUTLINE"-500,1450,450,-1400"
NEEDS_NO_SIZE"TRUE"
PART_NUMBER"AJ051610U03";
"EE_DAT"
$PN"FJ3"17;
"EE_CLK"
$PN"FF5"19;
"CLKREQ_N \B"
$PN"G35"28;
"TEST2"
$PN"FF30"64;
"TEST1"
$PN"FF27"62;
"TEST0"
$PN"FF24"59;
"T_SENSE"
$PN"E30"8;
"SMBDAT"
$PN"B28"54;
"SMBCLK"
$PN"B31"55;
"SMB_ADDR3"
$PN"B25"58;
"SMB_ADDR2"
$PN"B23"57;
"SMB_ADDR1"
$PN"F34"56;
"SCAN_MODE"
$PN"FF33"29;
"RXDET_BYP"
$PN"E11"30;
"RESET_N \B"
$PN"FF11"24;
"REFCLKP"
$PN"FJ16"63;
"REFCLKN"
$PN"FF18"67;
"REFCLK_OUTP"
$PN"B16"0;
"REFCLK_OUTN"
$PN"E18"0;
"PERST_N \B"
$PN"F2"25;
"MODE"
$PN"FJ9"31;
"JTAG_TRST_N \B"
$PN"E8"69;
"JTAG_TMS"
$PN"B12"71;
"JTAG_TEST_MODE"
$PN"FF8"72;
"JTAG_TDO"
$PN"B9"32;
"JTAG_TDI"
$PN"B6"70;
"JTAG_TCK"
$PN"B3"33;
"INT_N \B"
$PN"FJ31"0;
"GPIO3"
$PN"FJ28"50;
"GPIO2"
$PN"FJ25"40;
"GPIO1"
$PN"FJ23"0;
"GPIO0"
$PN"FJ6"0;
%"Q_RES"
"1","(-2725,3150)","0","pure_quanta","I84";
;
LOCATION"R1400"
$SEC"1"
CDS_SEC"1"
PACK_TYPE"0201LF"
MATERIAL"CHIP"
VALUE"1K"
CDS_LIB"pure_quanta"
WATTAGE"1/20W"
TOLERANCE"1%"
PART_NUMBER"CS21001FE07";
"B"
$PN"2"13;
"A"
$PN"1"69;
%"UNIVERSAL_GND"
"1","(-1975,3150)","1","pure_quanta_power","I88";
;
CDS_LIB"pure_quanta_power"
HDL_POWER"GND";
"A"13;
%"Q_RES"
"2","(-8350,4950)","0","pure_quanta","I9";
;
LOCATION"R1074"
$SEC"1"
CDS_SEC"1"
MATERIAL"CHIP"
WATTAGE"1/20W"
VALUE"4.7K"
TOLERANCE"5%"
PACK_TYPE"0201LF"
CDS_LIB"pure_quanta"
PART_NUMBER"CS24701JE04";
"A"
$PN"1"51;
"B"
$PN"2"37;
%"GND"
"1","(-1375,2825)","0","pure_quanta_power","I94";
;
CDS_LIB"pure_quanta_power"
SIZE"1B"
BOM_COST"MEM"
HDL_POWER"GND";
"A<SIZE-1..0>\NAC"14;
%"Q_RES"
"2","(-1375,3225)","0","pure_quanta","I95";
;
LOCATION"R1406"
$SEC"1"
CDS_SEC"1"
VALUE"10K"
WATTAGE"1/20W"
MATERIAL"CHIP"
TOLERANCE"1%"
PACK_TYPE"0201LF"
CDS_LIB"pure_quanta"
PART_NUMBER"CS31001FE17";
"A"
$PN"1"39;
"B"
$PN"2"14;
%"Q_RES"
"2","(-1375,3750)","0","pure_quanta","I96";
;
LOCATION"R1405"
$SEC"1"
CDS_SEC"1"
PACK_TYPE"0201LF"
VALUE"1K"
MATERIAL"EMPTY"
WATTAGE"1/20W"
TOLERANCE"1%"
CDS_LIB"pure_quanta"
PART_NUMBER"CS21001FE07";
"A"
$PN"1"15;
"B"
$PN"2"39;
%"P1V0"
"1","(-1375,4150)","0","pure_quanta_power","I97";
;
HDL_POWER"P1V8_CPU0_RT_1D"
CDS_LIB"pure_quanta_power";
"A"15;
%"Q_RES"
"1","(-2700,2200)","0","pure_quanta","I99";
;
LOCATION"R1404"
$SEC"1"
CDS_SEC"1"
PACK_TYPE"0201LF"
VALUE"4.7K"
MATERIAL"CHIP"
WATTAGE"1/20W"
TOLERANCE"5%"
CDS_LIB"pure_quanta"
PART_NUMBER"CS24701JE04";
"B"
$PN"2"1;
"A"
$PN"1"28;
END.
